# T6G (Grand Teton) — schematic parts with pin connectivity, parts 2606–2606 of 8303; source: Cadence DE-HDL packaged netlist (pstxprt.dat, pstxnet.dat, pstchip.dat)

J26  SCONN288_DDR506112002KQ  IO  pkg DDR288S_1-1VXC  page 99
  1  VIN_BULK0  POWER  = P12V_MEM_CPU1
  2  RFU0  TRI  = NC
  3  VIN_MGMT  POWER  = P3V3_AUX
  4  HSCL  IN  = I3C_SPD_DDRB_CPU1_SCL
  5  HSDA  BI  = I3C_SPD_DDRB_CPU1_SDA
  6  VSS0  POWER  = GND
  7  DQ0_A  BI  = M_B_CPU1_SA_DQ<0>
  8  VSS1  POWER  = GND
  9  DQ1_A  BI  = M_B_CPU1_SA_DQ<1>
  10  VSS2  POWER  = GND
  11  DQS0_A_T  BI  = M_B_CPU1_SA_DQS_DP<0>
  12  DQS0_A_C  BI  = M_B_CPU1_SA_DQS_DN<0>
  13  VSS3  POWER  = GND
  14  DQ4_A  BI  = M_B_CPU1_SA_DQ<4>
  15  VSS4  POWER  = GND
  16  DQ5_A  BI  = M_B_CPU1_SA_DQ<5>
  17  VSS5  POWER  = GND
  18  DQ8_A  BI  = M_B_CPU1_SA_DQ<8>
  19  VSS6  POWER  = GND
  20  DQ9_A  BI  = M_B_CPU1_SA_DQ<9>
  21  VSS7  POWER  = GND
  22  DQS1_A_T  BI  = M_B_CPU1_SA_DQS_DP<1>
  23  DQS1_A_C  BI  = M_B_CPU1_SA_DQS_DN<1>
  24  VSS8  POWER  = GND
  25  DQ12_A  BI  = M_B_CPU1_SA_DQ<12>
  26  VSS9  POWER  = GND
  27  DQ13_A  BI  = M_B_CPU1_SA_DQ<13>
  28  VSS10  POWER  = GND
  29  DQ16_A  BI  = M_B_CPU1_SA_DQ<16>
  30  VSS11  POWER  = GND
  31  DQ17_A  BI  = M_B_CPU1_SA_DQ<17>
  32  VSS12  POWER  = GND
  33  DQS2_A_T  BI  = M_B_CPU1_SA_DQS_DP<2>
  34  DQS2_A_C  BI  = M_B_CPU1_SA_DQS_DN<2>
  35  VSS13  POWER  = GND
  36  DQ20_A  BI  = M_B_CPU1_SA_DQ<20>
  37  VSS14  POWER  = GND
  38  DQ21_A  BI  = M_B_CPU1_SA_DQ<21>
  39  VSS15  POWER  = GND
  40  DQ24_A  BI  = M_B_CPU1_SA_DQ<24>
  41  VSS16  POWER  = GND
  42  DQ25_A  BI  = M_B_CPU1_SA_DQ<25>
  43  VSS17  POWER  = GND
  44  DQS3_A_T  BI  = M_B_CPU1_SA_DQS_DP<3>
  45  DQS3_A_C  BI  = M_B_CPU1_SA_DQS_DN<3>
  46  VSS18  POWER  = GND
  47  DQ28_A  BI  = M_B_CPU1_SA_DQ<28>
  48  VSS19  POWER  = GND
  49  DQ29_A  BI  = M_B_CPU1_SA_DQ<29>
  50  VSS20  POWER  = GND
  51  CB0_A  BI  = M_B_CPU1_SA_CB<0>
  52  VSS21  POWER  = GND
  53  CB1_A  BI  = M_B_CPU1_SA_CB<1>
  54  VSS22  POWER  = GND
  55  DQS4_A_T  BI  = M_B_CPU1_SA_DQS_DP<4>
  56  DQS4_A_C  BI  = M_B_CPU1_SA_DQS_DN<4>
  57  VSS23  POWER  = GND
  58  CB4_A  BI  = M_B_CPU1_SA_CB<4>
  59  VSS24  POWER  = GND
  60  CB5_A  BI  = M_B_CPU1_SA_CB<5>
  61  VSS25  POWER  = GND
  62  ALERT_N  OUT  = M_B_CPU1_ALERT_N
  63  VSS26  POWER  = GND
  64  CS0_A_N  IN  = M_B_CPU1_SA_CS_N<0>
  65  VSS27  POWER  = GND
  66  CA0_A  IN  = M_B_CPU1_SA_CA<0>
  67  VSS28  POWER  = GND
  68  CA2_A  IN  = M_B_CPU1_SA_CA<2>
  69  VSS29  POWER  = GND
  70  CA4_A  IN  = M_B_CPU1_SA_CA<4>
  71  VSS30  POWER  = GND
  72  CA6_A  IN  = M_B_CPU1_SA_CA<6>
  73  VSS31  POWER  = GND
  74  PAR_A  IN  = M_B_CPU1_SA_PAR
  75  VSS32  POWER  = GND
  76  CA0_B  IN  = M_B_CPU1_SB_CA<0>
  77  VSS33  POWER  = GND
  78  CA2_B  IN  = M_B_CPU1_SB_CA<2>
  79  VSS34  POWER  = GND
  80  CA4_B  IN  = M_B_CPU1_SB_CA<4>
  81  VSS35  POWER  = GND
  82  CA6_B  IN  = M_B_CPU1_SB_CA<6>
  83  VSS36  POWER  = GND
  84  CS0_B_N  IN  = M_B_CPU1_SB_CS_N<0>
  85  VSS37  POWER  = GND
  86  \lbd||rsp_a_n\  OUT  = M_B_CPU1_SA_RSP<0>
  87  \lbs||rsp_b_n\  OUT  = M_B_CPU1_SB_RSP<0>
  88  VSS38  POWER  = GND
  89  CB4_B  BI  = M_B_CPU1_SB_CB<4>
  90  VSS39  POWER  = GND
  91  CB5_B  BI  = M_B_CPU1_SB_CB<5>
  92  VSS40  POWER  = GND
  93  \dqs9_b_t||tdqs9_b_t||dbi4_b_n\  BI  = M_B_CPU1_SB_DQS_DP<9>
  94  \dqs9_b_c||tdqs9_b_c\  BI  = M_B_CPU1_SB_DQS_DN<9>
  95  VSS41  POWER  = GND
  96  CB0_B  BI  = M_B_CPU1_SB_CB<0>
  97  VSS42  POWER  = GND
  98  CB1_B  BI  = M_B_CPU1_SB_CB<1>
  99  VSS43  POWER  = GND
  100  DQ0_B  BI  = M_B_CPU1_SB_DQ<0>
  101  VSS44  POWER  = GND
  102  DQ1_B  BI  = M_B_CPU1_SB_DQ<1>
  103  VSS45  POWER  = GND
  104  DQS0_B_T  BI  = M_B_CPU1_SB_DQS_DP<0>
  105  DQS0_B_C  BI  = M_B_CPU1_SB_DQS_DN<0>
  106  VSS46  POWER  = GND
  107  DQ4_B  BI  = M_B_CPU1_SB_DQ<4>
  108  VSS47  POWER  = GND
  109  DQ5_B  BI  = M_B_CPU1_SB_DQ<5>
  110  VSS48  POWER  = GND
  111  DQ8_B  BI  = M_B_CPU1_SB_DQ<8>
  112  VSS49  POWER  = GND
  113  DQ9_B  BI  = M_B_CPU1_SB_DQ<9>
  114  VSS50  POWER  = GND
  115  DQS1_B_T  BI  = M_B_CPU1_SB_DQS_DP<1>
  116  DQS1_B_C  BI  = M_B_CPU1_SB_DQS_DN<1>
  117  VSS51  POWER  = GND
  118  DQ12_B  BI  = M_B_CPU1_SB_DQ<12>
  119  VSS52  POWER  = GND
  120  DQ13_B  BI  = M_B_CPU1_SB_DQ<13>
  121  VSS53  POWER  = GND
  122  DQ16_B  BI  = M_B_CPU1_SB_DQ<16>
  123  VSS54  POWER  = GND
  124  DQ17_B  BI  = M_B_CPU1_SB_DQ<17>
  125  VSS55  POWER  = GND
  126  DQS2_B_T  BI  = M_B_CPU1_SB_DQS_DP<2>
  127  DQS2_B_C  BI  = M_B_CPU1_SB_DQS_DN<2>
  128  VSS56  POWER  = GND
  129  DQ20_B  BI  = M_B_CPU1_SB_DQ<20>
  130  VSS57  POWER  = GND
  131  DQ21_B  BI  = M_B_CPU1_SB_DQ<21>
  132  VSS58  POWER  = GND
  133  DQ24_B  BI  = M_B_CPU1_SB_DQ<24>
  134  VSS59  POWER  = GND
  135  DQ25_B  BI  = M_B_CPU1_SB_DQ<25>
  136  VSS60  POWER  = GND
  137  DQS3_B_T  BI  = M_B_CPU1_SB_DQS_DP<3>
  138  DQS3_B_C  BI  = M_B_CPU1_SB_DQS_DN<3>
  139  VSS61  POWER  = GND
  140  DQ28_B  BI  = M_B_CPU1_SB_DQ<28>
  141  VSS62  POWER  = GND
  142  DQ29_B  BI  = M_B_CPU1_SB_DQ<29>
  143  VSS63  POWER  = GND
  144  RFU1  TRI  = NC
  145  VIN_BULK1  POWER  = P12V_MEM_CPU1
  146  VIN_BULK2  POWER  = P12V_MEM_CPU1
  147  \pwr_good||fail_n\  BI  = PWRGD_CHB_CPU1_DIMM
  148  HAS  IN  = PD_CHB_CPU1_DIMM_SAA
  149  RFU2  TRI  = NC
  150  RFU3  TRI  = NC
  151  VSS64  POWER  = GND
  152  DQ2_A  BI  = M_B_CPU1_SA_DQ<2>
  153  VSS65  POWER  = GND
  154  DQ3_A  BI  = M_B_CPU1_SA_DQ<3>
  155  VSS66  POWER  = GND
  156  \dqs5_a_c||tdqs5_a_c||dqs5_a_t||tdqs5_a_t\  BI  = M_B_CPU1_SA_DQS_DN<5>
  157  \dqs5_a_t||tdqs5_a_t\  BI  = M_B_CPU1_SA_DQS_DP<5>
  158  VSS67  POWER  = GND
  159  DQ6_A  BI  = M_B_CPU1_SA_DQ<6>
  160  VSS68  POWER  = GND
  161  DQ7_A  BI  = M_B_CPU1_SA_DQ<7>
  162  VSS69  POWER  = GND
  163  DQ10_A  BI  = M_B_CPU1_SA_DQ<10>
  164  VSS70  POWER  = GND
  165  DQ11_A  BI  = M_B_CPU1_SA_DQ<11>
  166  VSS71  POWER  = GND
  167  \dqs6_a_c||tdqs6_a_c||dqs6_a_t||tdqs6_a_t\  BI  = M_B_CPU1_SA_DQS_DN<6>
  168  \dqs6_a_t||tdqs6_a_t\  BI  = M_B_CPU1_SA_DQS_DP<6>
  169  VSS72  POWER  = GND
  170  DQ14_A  BI  = M_B_CPU1_SA_DQ<14>
  171  VSS73  POWER  = GND
  172  DQ15_A  BI  = M_B_CPU1_SA_DQ<15>
  173  VSS74  POWER  = GND
  174  DQ18_A  BI  = M_B_CPU1_SA_DQ<18>
  175  VSS75  POWER  = GND
  176  DQ19_A  BI  = M_B_CPU1_SA_DQ<19>
  177  VSS76  POWER  = GND
  178  \dqs7_a_c||tdqs7_a_c\  BI  = M_B_CPU1_SA_DQS_DN<7>
  179  \dqs7_a_t||tdqs7_a_t\  BI  = M_B_CPU1_SA_DQS_DP<7>
  180  VSS77  POWER  = GND
  181  DQ22_A  BI  = M_B_CPU1_SA_DQ<22>
  182  VSS78  POWER  = GND
  183  DQ23_A  BI  = M_B_CPU1_SA_DQ<23>
  184  VSS79  POWER  = GND
  185  DQ26_A  BI  = M_B_CPU1_SA_DQ<26>
  186  VSS80  POWER  = GND
  187  DQ27_A  BI  = M_B_CPU1_SA_DQ<27>
  188  VSS81  POWER  = GND
  189  \dqs8_a_c||tdqs8_a_c\  BI  = M_B_CPU1_SA_DQS_DN<8>
  190  \dqs8_a_t||tdqs8_a_t\  BI  = M_B_CPU1_SA_DQS_DP<8>
  191  VSS82  POWER  = GND
  192  DQ30_A  BI  = M_B_CPU1_SA_DQ<30>
  193  VSS83  POWER  = GND
  194  DQ31_A  BI  = M_B_CPU1_SA_DQ<31>
  195  VSS84  POWER  = GND
  196  CB2_A  BI  = M_B_CPU1_SA_CB<2>
  197  VSS85  POWER  = GND
  198  CB3_A  BI  = M_B_CPU1_SA_CB<3>
  199  VSS86  POWER  = GND
  200  \dqs9_a_c||tdqs9_a_c\  BI  = M_B_CPU1_SA_DQS_DN<9>
  201  \dqs9_a_t||tdqs9_a_t\  BI  = M_B_CPU1_SA_DQS_DP<9>
  202  VSS87  POWER  = GND
  203  CB6_A  BI  = M_B_CPU1_SA_CB<6>
  204  VSS88  POWER  = GND
  205  CB7_A  BI  = M_B_CPU1_SA_CB<7>
  206  VSS89  POWER  = GND
  207  RESET_N  IN  = M_B_CPU1_RESET_N
  208  VSS90  POWER  = GND
  209  CS1_A_N  IN  = M_B_CPU1_SA_CS_N<1>
  210  VSS91  POWER  = GND
  211  CA1_A  IN  = M_B_CPU1_SA_CA<1>
  212  VSS92  POWER  = GND
  213  CA3_A  IN  = M_B_CPU1_SA_CA<3>
  214  VSS93  POWER  = GND
  215  CA5_A  IN  = M_B_CPU1_SA_CA<5>
  216  VSS94  POWER  = GND
  217  CK_T  IN  = M_B_CPU1_CLK_DP<0>
  218  CK_C  IN  = M_B_CPU1_CLK_DN<0>
  219  VSS95  POWER  = GND
  220  RFU4  TRI  = NC
  221  CA1_B  IN  = M_B_CPU1_SB_CA<1>
  222  VSS96  POWER  = GND
  223  CA3_B  IN  = M_B_CPU1_SB_CA<3>
  224  VSS97  POWER  = GND
  225  CA5_B  IN  = M_B_CPU1_SB_CA<5>
  226  VSS98  POWER  = GND
  227  PAR_B  IN  = M_B_CPU1_SB_PAR
  228  VSS99  POWER  = GND
  229  CS1_B_N  IN  = M_B_CPU1_SB_CS_N<1>
  230  VSS100  POWER  = GND
  231  RFU5  TRI  = NC
  232  RFU6  TRI  = NC
  233  VSS101  POWER  = GND
  234  CB6_B  BI  = M_B_CPU1_SB_CB<6>
  235  VSS102  POWER  = GND
  236  CB7_B  BI  = M_B_CPU1_SB_CB<7>
  237  VSS103  POWER  = GND
  238  DQS4_B_C  BI  = M_B_CPU1_SB_DQS_DN<4>
  239  DQS4_B_T  BI  = M_B_CPU1_SB_DQS_DP<4>
  240  VSS104  POWER  = GND
  241  CB2_B  BI  = M_B_CPU1_SB_CB<2>
  242  VSS105  POWER  = GND
  243  CB3_B  BI  = M_B_CPU1_SB_CB<3>
  244  VSS106  POWER  = GND
  245  DQ2_B  BI  = M_B_CPU1_SB_DQ<2>
  246  VSS107  POWER  = GND
  247  DQ3_B  BI  = M_B_CPU1_SB_DQ<3>
  248  VSS108  POWER  = GND
  249  \dqs5_b_c||tdqs5_b_c\  BI  = M_B_CPU1_SB_DQS_DN<5>
  250  \dqs5_b_t||tdqs5_b_t\  BI  = M_B_CPU1_SB_DQS_DP<5>
  251  VSS109  POWER  = GND
  252  DQ6_B  BI  = M_B_CPU1_SB_DQ<6>
  253  VSS110  POWER  = GND
  254  DQ7_B  BI  = M_B_CPU1_SB_DQ<7>
  255  VSS111  POWER  = GND
  256  DQ10_B  BI  = M_B_CPU1_SB_DQ<10>
  257  VSS112  POWER  = GND
  258  DQ11_B  BI  = M_B_CPU1_SB_DQ<11>
  259  VSS113  POWER  = GND
  260  \dqs6_b_c||tdqs6_b_c\  BI  = M_B_CPU1_SB_DQS_DN<6>
  261  \dqs6_b_t||tdqs6_b_t\  BI  = M_B_CPU1_SB_DQS_DP<6>
  262  VSS114  POWER  = GND
  263  DQ14_B  BI  = M_B_CPU1_SB_DQ<14>
  264  VSS115  POWER  = GND
  265  DQ15_B  BI  = M_B_CPU1_SB_DQ<15>
  266  VSS116  POWER  = GND
  267  DQ18_B  BI  = M_B_CPU1_SB_DQ<18>
  268  VSS117  POWER  = GND
  269  DQ19_B  BI  = M_B_CPU1_SB_DQ<19>
  270  VSS118  POWER  = GND
  271  \dqs7_b_c||tdqs7_b_c\  BI  = M_B_CPU1_SB_DQS_DN<7>
  272  \dqs7_b_t||tdqs7_b_t\  BI  = M_B_CPU1_SB_DQS_DP<7>
  273  VSS119  POWER  = GND
  274  DQ22_B  BI  = M_B_CPU1_SB_DQ<22>
  275  VSS120  POWER  = GND
  276  DQ23_B  BI  = M_B_CPU1_SB_DQ<23>
  277  VSS121  POWER  = GND
  278  DQ26_B  BI  = M_B_CPU1_SB_DQ<26>
  279  VSS122  POWER  = GND
  280  DQ27_B  BI  = M_B_CPU1_SB_DQ<27>
  281  VSS123  POWER  = GND
  282  \dqs8_b_c||tdqs8_b_c\  BI  = M_B_CPU1_SB_DQS_DN<8>
  283  \dqs8_b_t||tdqs8_b_t\  BI  = M_B_CPU1_SB_DQS_DP<8>
  284  VSS124  POWER  = GND
  285  DQ30_B  BI  = M_B_CPU1_SB_DQ<30>
  286  VSS125  POWER  = GND
  287  DQ31_B  BI  = M_B_CPU1_SB_DQ<31>
  288  VSS126  POWER  = GND
  G1  G1  POWER  = GND
  G2  G2  POWER  = GND
  G3  G3  POWER  = GND
